(kicad_pcb
	(version 20260206)
	(generator "pcbnew")
	(generator_version "10.0")
	(general
		(thickness 1.6)
		(legacy_teardrops no)
	)
	(paper "A4")
	(title_block
		(title "01162023_DA0F0TEBIF0_F0T_Expander_BD_F_brd_V02_OCP.brd")
		(comment 1 "Grand Teton / footprints 2924-2930 of 9728")
	)
	(layers
		(0 "F.Cu" signal "TOP")
		(4 "In1.Cu" signal "GND")
		(6 "In2.Cu" signal "VCC")
		(8 "In3.Cu" signal "VCC1")
		(10 "In4.Cu" signal "GND1")
		(12 "In5.Cu" signal "IN1")
		(14 "In6.Cu" signal "GND2")
		(16 "In7.Cu" signal "IN2")
		(18 "In8.Cu" signal "GND3")
		(20 "In9.Cu" signal "IN3")
		(22 "In10.Cu" signal "GND4")
		(24 "In11.Cu" signal "IN4")
		(26 "In12.Cu" signal "GND5")
		(28 "In13.Cu" signal "IN5")
		(30 "In14.Cu" signal "GND6")
		(32 "In15.Cu" signal "IN6")
		(34 "In16.Cu" signal "GND7")
		(2 "B.Cu" signal "BOTTOM")
		(9 "F.Adhes" user "F.Adhesive")
		(11 "B.Adhes" user "B.Adhesive")
		(13 "F.Paste" user "Package Geometry/Pastemask Top")
		(15 "B.Paste" user "Package Geometry/Pastemask Bottom")
		(5 "F.SilkS" user "Ref Des/Silkscreen Top")
		(7 "B.SilkS" user "Ref Des/Silkscreen Bottom")
		(1 "F.Mask" user "Board Geometry/Soldermask Top")
		(3 "B.Mask" user "Board Geometry/Soldermask Bottom")
		(17 "Dwgs.User" user "User.Drawings")
		(19 "Cmts.User" user "User.Comments")
		(21 "Eco1.User" user "User.Eco1")
		(23 "Eco2.User" user "User.Eco2")
		(25 "Edge.Cuts" user "Board Geometry/Outline")
		(27 "Margin" user)
		(31 "F.CrtYd" user "Package Geometry/Place Bound Top")
		(29 "B.CrtYd" user "Package Geometry/Place Bound Bottom")
		(35 "F.Fab" user "Ref Des/Assembly Top")
		(33 "B.Fab" user "Ref Des/Assembly Bottom")
	)
	(footprint ""
		(layer "F.Cu")
		(at 52.243736 -46.90491)
		(property "Reference" "R520"
			(at 0 0 0)
			(layer "F.SilkS")
			(hide yes)
			(effects
				(font
					(size 1.27 1.27)
				)
			)
		)
		(property "Value" ""
			(at 0 0 0)
			(layer "F.Fab")
			(effects
				(font
					(size 1.27 1.27)
				)
			)
		)
		(duplicate_pad_numbers_are_jumpers no)
		(fp_line
			(start -0.7874 -0.4064)
			(end 0.7874 -0.4064)
			(stroke
				(width 0.1524)
				(type default)
			)
			(layer "F.SilkS")
		)
		(fp_line
			(start -0.7874 0.4064)
			(end -0.7874 -0.4064)
			(stroke
				(width 0.1524)
				(type default)
			)
			(layer "F.SilkS")
		)
		(fp_line
			(start 0.7874 -0.4064)
			(end 0.7874 0.4064)
			(stroke
				(width 0.1524)
				(type default)
			)
			(layer "F.SilkS")
		)
		(fp_line
			(start 0.7874 0.4064)
			(end -0.7874 0.4064)
			(stroke
				(width 0.1524)
				(type default)
			)
			(layer "F.SilkS")
		)
		(fp_line
			(start -0.67945 -0.305054)
			(end -0.12065 -0.305054)
			(stroke
				(width 0.1)
				(type default)
			)
			(layer "F.Fab")
		)
		(fp_line
			(start -0.67945 0.3048)
			(end -0.67945 -0.305054)
			(stroke
				(width 0.1)
				(type default)
			)
			(layer "F.Fab")
		)
		(fp_line
			(start -0.12065 -0.305054)
			(end -0.12065 -0.2794)
			(stroke
				(width 0.1)
				(type default)
			)
			(layer "F.Fab")
		)
		(fp_line
			(start -0.12065 -0.2794)
			(end 0.12065 -0.2794)
			(stroke
				(width 0.1)
				(type default)
			)
			(layer "F.Fab")
		)
		(fp_line
			(start -0.12065 0.2794)
			(end -0.12065 0.3048)
			(stroke
				(width 0.1)
				(type default)
			)
			(layer "F.Fab")
		)
		(fp_line
			(start -0.12065 0.3048)
			(end -0.67945 0.3048)
			(stroke
				(width 0.1)
				(type default)
			)
			(layer "F.Fab")
		)
		(fp_line
			(start 0.120396 0.2794)
			(end -0.12065 0.2794)
			(stroke
				(width 0.1)
				(type default)
			)
			(layer "F.Fab")
		)
		(fp_line
			(start 0.120396 0.3048)
			(end 0.120396 0.2794)
			(stroke
				(width 0.1)
				(type default)
			)
			(layer "F.Fab")
		)
		(fp_line
			(start 0.12065 -0.3048)
			(end 0.67945 -0.3048)
			(stroke
				(width 0.1)
				(type default)
			)
			(layer "F.Fab")
		)
		(fp_line
			(start 0.12065 -0.2794)
			(end 0.12065 -0.3048)
			(stroke
				(width 0.1)
				(type default)
			)
			(layer "F.Fab")
		)
		(fp_line
			(start 0.67945 -0.3048)
			(end 0.67945 0.3048)
			(stroke
				(width 0.1)
				(type default)
			)
			(layer "F.Fab")
		)
		(fp_line
			(start 0.67945 0.3048)
			(end 0.120396 0.3048)
			(stroke
				(width 0.1)
				(type default)
			)
			(layer "F.Fab")
		)
		(pad "1" smd circle
			(at -0.40005 0)
			(size 0 0)
			(layers "F.Cu" "F.Mask" "F.Paste")
			(net "SSD1_ADC_ALERT_N")
		)
		(pad "2" smd circle
			(at 0.40005 0)
			(size 0 0)
			(layers "F.Cu" "F.Mask" "F.Paste")
			(net "SSD_0_7_ADC_ALERT_N")
		)
	)
	(footprint ""
		(layer "F.Cu")
		(at 121.39422 -34.248852)
		(property "Reference" "R5667"
			(at 0 0 0)
			(layer "F.SilkS")
			(hide yes)
			(effects
				(font
					(size 1.27 1.27)
				)
			)
		)
		(property "Value" ""
			(at 0 0 0)
			(layer "F.Fab")
			(effects
				(font
					(size 1.27 1.27)
				)
			)
		)
		(duplicate_pad_numbers_are_jumpers no)
		(fp_line
			(start -0.7874 -0.4064)
			(end 0.7874 -0.4064)
			(stroke
				(width 0.1524)
				(type default)
			)
			(layer "F.SilkS")
		)
		(fp_line
			(start -0.7874 0.4064)
			(end -0.7874 -0.4064)
			(stroke
				(width 0.1524)
				(type default)
			)
			(layer "F.SilkS")
		)
		(fp_line
			(start 0.7874 -0.4064)
			(end 0.7874 0.4064)
			(stroke
				(width 0.1524)
				(type default)
			)
			(layer "F.SilkS")
		)
		(fp_line
			(start 0.7874 0.4064)
			(end -0.7874 0.4064)
			(stroke
				(width 0.1524)
				(type default)
			)
			(layer "F.SilkS")
		)
		(fp_line
			(start -0.67945 -0.305054)
			(end -0.12065 -0.305054)
			(stroke
				(width 0.1)
				(type default)
			)
			(layer "F.Fab")
		)
		(fp_line
			(start -0.67945 0.3048)
			(end -0.67945 -0.305054)
			(stroke
				(width 0.1)
				(type default)
			)
			(layer "F.Fab")
		)
		(fp_line
			(start -0.12065 -0.305054)
			(end -0.12065 -0.2794)
			(stroke
				(width 0.1)
				(type default)
			)
			(layer "F.Fab")
		)
		(fp_line
			(start -0.12065 -0.2794)
			(end 0.12065 -0.2794)
			(stroke
				(width 0.1)
				(type default)
			)
			(layer "F.Fab")
		)
		(fp_line
			(start -0.12065 0.2794)
			(end -0.12065 0.3048)
			(stroke
				(width 0.1)
				(type default)
			)
			(layer "F.Fab")
		)
		(fp_line
			(start -0.12065 0.3048)
			(end -0.67945 0.3048)
			(stroke
				(width 0.1)
				(type default)
			)
			(layer "F.Fab")
		)
		(fp_line
			(start 0.120396 0.2794)
			(end -0.12065 0.2794)
			(stroke
				(width 0.1)
				(type default)
			)
			(layer "F.Fab")
		)
		(fp_line
			(start 0.120396 0.3048)
			(end 0.120396 0.2794)
			(stroke
				(width 0.1)
				(type default)
			)
			(layer "F.Fab")
		)
		(fp_line
			(start 0.12065 -0.3048)
			(end 0.67945 -0.3048)
			(stroke
				(width 0.1)
				(type default)
			)
			(layer "F.Fab")
		)
		(fp_line
			(start 0.12065 -0.2794)
			(end 0.12065 -0.3048)
			(stroke
				(width 0.1)
				(type default)
			)
			(layer "F.Fab")
		)
		(fp_line
			(start 0.67945 -0.3048)
			(end 0.67945 0.3048)
			(stroke
				(width 0.1)
				(type default)
			)
			(layer "F.Fab")
		)
		(fp_line
			(start 0.67945 0.3048)
			(end 0.120396 0.3048)
			(stroke
				(width 0.1)
				(type default)
			)
			(layer "F.Fab")
		)
		(pad "1" smd circle
			(at -0.40005 0)
			(size 0 0)
			(layers "F.Cu" "F.Mask" "F.Paste")
			(net "RST_SMB_SSD4_ISO_N")
		)
		(pad "2" smd circle
			(at 0.40005 0)
			(size 0 0)
			(layers "F.Cu" "F.Mask" "F.Paste")
			(net "P3V3_SSD4")
		)
	)
	(footprint ""
		(layer "F.Cu")
		(at 196.441822 -27.006296 -90)
		(property "Reference" "PR7114"
			(at 0 0 270)
			(layer "F.SilkS")
			(hide yes)
			(effects
				(font
					(size 1.27 1.27)
				)
			)
		)
		(property "Value" ""
			(at 0 0 270)
			(layer "F.Fab")
			(effects
				(font
					(size 1.27 1.27)
				)
			)
		)
		(duplicate_pad_numbers_are_jumpers no)
		(fp_line
			(start -0.7874 0.4064)
			(end -0.7874 -0.4064)
			(stroke
				(width 0.1524)
				(type default)
			)
			(layer "F.SilkS")
		)
		(fp_line
			(start 0.7874 0.4064)
			(end -0.7874 0.4064)
			(stroke
				(width 0.1524)
				(type default)
			)
			(layer "F.SilkS")
		)
		(fp_line
			(start -0.7874 -0.4064)
			(end 0.7874 -0.4064)
			(stroke
				(width 0.1524)
				(type default)
			)
			(layer "F.SilkS")
		)
		(fp_line
			(start 0.7874 -0.4064)
			(end 0.7874 0.4064)
			(stroke
				(width 0.1524)
				(type default)
			)
			(layer "F.SilkS")
		)
		(fp_line
			(start -0.67945 0.3048)
			(end -0.67945 -0.305054)
			(stroke
				(width 0.1)
				(type default)
			)
			(layer "F.Fab")
		)
		(fp_line
			(start -0.12065 0.3048)
			(end -0.67945 0.3048)
			(stroke
				(width 0.1)
				(type default)
			)
			(layer "F.Fab")
		)
		(fp_line
			(start 0.120396 0.3048)
			(end 0.120396 0.2794)
			(stroke
				(width 0.1)
				(type default)
			)
			(layer "F.Fab")
		)
		(fp_line
			(start 0.67945 0.3048)
			(end 0.120396 0.3048)
			(stroke
				(width 0.1)
				(type default)
			)
			(layer "F.Fab")
		)
		(fp_line
			(start -0.12065 0.2794)
			(end -0.12065 0.3048)
			(stroke
				(width 0.1)
				(type default)
			)
			(layer "F.Fab")
		)
		(fp_line
			(start 0.120396 0.2794)
			(end -0.12065 0.2794)
			(stroke
				(width 0.1)
				(type default)
			)
			(layer "F.Fab")
		)
		(fp_line
			(start -0.12065 -0.2794)
			(end 0.12065 -0.2794)
			(stroke
				(width 0.1)
				(type default)
			)
			(layer "F.Fab")
		)
		(fp_line
			(start 0.12065 -0.2794)
			(end 0.12065 -0.3048)
			(stroke
				(width 0.1)
				(type default)
			)
			(layer "F.Fab")
		)
		(fp_line
			(start 0.12065 -0.3048)
			(end 0.67945 -0.3048)
			(stroke
				(width 0.1)
				(type default)
			)
			(layer "F.Fab")
		)
		(fp_line
			(start 0.67945 -0.3048)
			(end 0.67945 0.3048)
			(stroke
				(width 0.1)
				(type default)
			)
			(layer "F.Fab")
		)
		(fp_line
			(start -0.67945 -0.305054)
			(end -0.12065 -0.305054)
			(stroke
				(width 0.1)
				(type default)
			)
			(layer "F.Fab")
		)
		(fp_line
			(start -0.12065 -0.305054)
			(end -0.12065 -0.2794)
			(stroke
				(width 0.1)
				(type default)
			)
			(layer "F.Fab")
		)
		(pad "1" smd circle
			(at -0.40005 0 270)
			(size 0 0)
			(layers "F.Cu" "F.Mask" "F.Paste")
			(net "P3V3_SSD7_CO_ILIMIT")
		)
		(pad "2" smd circle
			(at 0.40005 0 270)
			(size 0 0)
			(layers "F.Cu" "F.Mask" "F.Paste")
			(net "GND")
		)
	)
	(footprint ""
		(layer "F.Cu")
		(at 369.813586 -254.753364 -90)
		(property "Reference" "R6156"
			(at 0 0 270)
			(layer "F.SilkS")
			(hide yes)
			(effects
				(font
					(size 1.27 1.27)
				)
			)
		)
		(property "Value" ""
			(at 0 0 270)
			(layer "F.Fab")
			(effects
				(font
					(size 1.27 1.27)
				)
			)
		)
		(duplicate_pad_numbers_are_jumpers no)
		(fp_line
			(start -0.7874 0.4064)
			(end -0.7874 -0.4064)
			(stroke
				(width 0.1524)
				(type default)
			)
			(layer "F.SilkS")
		)
		(fp_line
			(start 0.7874 0.4064)
			(end -0.7874 0.4064)
			(stroke
				(width 0.1524)
				(type default)
			)
			(layer "F.SilkS")
		)
		(fp_line
			(start -0.7874 -0.4064)
			(end 0.7874 -0.4064)
			(stroke
				(width 0.1524)
				(type default)
			)
			(layer "F.SilkS")
		)
		(fp_line
			(start 0.7874 -0.4064)
			(end 0.7874 0.4064)
			(stroke
				(width 0.1524)
				(type default)
			)
			(layer "F.SilkS")
		)
		(fp_line
			(start -0.67945 0.3048)
			(end -0.67945 -0.305054)
			(stroke
				(width 0.1)
				(type default)
			)
			(layer "F.Fab")
		)
		(fp_line
			(start -0.12065 0.3048)
			(end -0.67945 0.3048)
			(stroke
				(width 0.1)
				(type default)
			)
			(layer "F.Fab")
		)
		(fp_line
			(start 0.120396 0.3048)
			(end 0.120396 0.2794)
			(stroke
				(width 0.1)
				(type default)
			)
			(layer "F.Fab")
		)
		(fp_line
			(start 0.67945 0.3048)
			(end 0.120396 0.3048)
			(stroke
				(width 0.1)
				(type default)
			)
			(layer "F.Fab")
		)
		(fp_line
			(start -0.12065 0.2794)
			(end -0.12065 0.3048)
			(stroke
				(width 0.1)
				(type default)
			)
			(layer "F.Fab")
		)
		(fp_line
			(start 0.120396 0.2794)
			(end -0.12065 0.2794)
			(stroke
				(width 0.1)
				(type default)
			)
			(layer "F.Fab")
		)
		(fp_line
			(start -0.12065 -0.2794)
			(end 0.12065 -0.2794)
			(stroke
				(width 0.1)
				(type default)
			)
			(layer "F.Fab")
		)
		(fp_line
			(start 0.12065 -0.2794)
			(end 0.12065 -0.3048)
			(stroke
				(width 0.1)
				(type default)
			)
			(layer "F.Fab")
		)
		(fp_line
			(start 0.12065 -0.3048)
			(end 0.67945 -0.3048)
			(stroke
				(width 0.1)
				(type default)
			)
			(layer "F.Fab")
		)
		(fp_line
			(start 0.67945 -0.3048)
			(end 0.67945 0.3048)
			(stroke
				(width 0.1)
				(type default)
			)
			(layer "F.Fab")
		)
		(fp_line
			(start -0.67945 -0.305054)
			(end -0.12065 -0.305054)
			(stroke
				(width 0.1)
				(type default)
			)
			(layer "F.Fab")
		)
		(fp_line
			(start -0.12065 -0.305054)
			(end -0.12065 -0.2794)
			(stroke
				(width 0.1)
				(type default)
			)
			(layer "F.Fab")
		)
		(pad "1" smd circle
			(at -0.40005 0 270)
			(size 0 0)
			(layers "F.Cu" "F.Mask" "F.Paste")
			(net "PEX3_SYS_ERR_R_N")
		)
		(pad "2" smd circle
			(at 0.40005 0 270)
			(size 0 0)
			(layers "F.Cu" "F.Mask" "F.Paste")
			(net "P1V8_PEX")
		)
	)
	(footprint ""
		(layer "F.Cu")
		(at 345.710002 -293.5351 90)
		(property "Reference" "PL13"
			(at -4.920234 22.928072 90)
			(unlocked yes)
			(layer "F.SilkS")
			(effects
				(font
					(size 0.7874 0.5842)
					(thickness 0.1524)
				)
				(justify left)
			)
		)
		(property "Value" ""
			(at 0 0 90)
			(layer "F.Fab")
			(effects
				(font
					(size 1.27 1.27)
				)
			)
		)
		(duplicate_pad_numbers_are_jumpers no)
		(fp_line
			(start 4.800092 -3.199892)
			(end 4.800092 -1.6764)
			(stroke
				(width 0.1524)
				(type default)
			)
			(layer "F.SilkS")
		)
		(fp_line
			(start -4.800092 -3.199892)
			(end 4.800092 -3.199892)
			(stroke
				(width 0.1524)
				(type default)
			)
			(layer "F.SilkS")
		)
		(fp_line
			(start -4.800092 -1.6764)
			(end -4.800092 -3.199892)
			(stroke
				(width 0.1524)
				(type default)
			)
			(layer "F.SilkS")
		)
		(fp_line
			(start 4.800092 1.6764)
			(end 4.800092 3.199892)
			(stroke
				(width 0.1524)
				(type default)
			)
			(layer "F.SilkS")
		)
		(fp_line
			(start 4.800092 3.199892)
			(end -4.800092 3.199892)
			(stroke
				(width 0.1524)
				(type default)
			)
			(layer "F.SilkS")
		)
		(fp_line
			(start -4.800092 3.199892)
			(end -4.800092 1.6764)
			(stroke
				(width 0.1524)
				(type default)
			)
			(layer "F.SilkS")
		)
		(fp_line
			(start 4.800092 -3.199892)
			(end 4.800092 3.199892)
			(stroke
				(width 0.1)
				(type default)
			)
			(layer "F.Fab")
		)
		(fp_line
			(start -4.800092 -3.199892)
			(end 4.800092 -3.199892)
			(stroke
				(width 0.1)
				(type default)
			)
			(layer "F.Fab")
		)
		(fp_line
			(start 4.800092 3.199892)
			(end -4.800092 3.199892)
			(stroke
				(width 0.1)
				(type default)
			)
			(layer "F.Fab")
		)
		(fp_line
			(start -4.800092 3.199892)
			(end -4.800092 -3.199892)
			(stroke
				(width 0.1)
				(type default)
			)
			(layer "F.Fab")
		)
		(pad "1" smd rect
			(at -3.074924 0 180)
			(size 3.0988 3.3528)
			(layers "F.Cu" "F.Mask" "F.Paste")
			(net "SW_P0V8_PEX2_PH2")
		)
		(pad "2" smd rect
			(at 3.074924 0 180)
			(size 3.0988 3.3528)
			(layers "F.Cu" "F.Mask" "F.Paste")
			(net "P0V8_PEX2")
		)
	)
	(footprint ""
		(layer "F.Cu")
		(at 216.480136 -181.613556 -90)
		(property "Reference" "R5297"
			(at 0 0 270)
			(layer "F.SilkS")
			(hide yes)
			(effects
				(font
					(size 1.27 1.27)
				)
			)
		)
		(property "Value" ""
			(at 0 0 270)
			(layer "F.Fab")
			(effects
				(font
					(size 1.27 1.27)
				)
			)
		)
		(duplicate_pad_numbers_are_jumpers no)
		(fp_line
			(start -0.7874 0.4064)
			(end -0.7874 -0.4064)
			(stroke
				(width 0.1524)
				(type default)
			)
			(layer "F.SilkS")
		)
		(fp_line
			(start 0.7874 0.4064)
			(end -0.7874 0.4064)
			(stroke
				(width 0.1524)
				(type default)
			)
			(layer "F.SilkS")
		)
		(fp_line
			(start -0.7874 -0.4064)
			(end 0.7874 -0.4064)
			(stroke
				(width 0.1524)
				(type default)
			)
			(layer "F.SilkS")
		)
		(fp_line
			(start 0.7874 -0.4064)
			(end 0.7874 0.4064)
			(stroke
				(width 0.1524)
				(type default)
			)
			(layer "F.SilkS")
		)
		(fp_line
			(start -0.67945 0.3048)
			(end -0.67945 -0.305054)
			(stroke
				(width 0.1)
				(type default)
			)
			(layer "F.Fab")
		)
		(fp_line
			(start -0.12065 0.3048)
			(end -0.67945 0.3048)
			(stroke
				(width 0.1)
				(type default)
			)
			(layer "F.Fab")
		)
		(fp_line
			(start 0.120396 0.3048)
			(end 0.120396 0.2794)
			(stroke
				(width 0.1)
				(type default)
			)
			(layer "F.Fab")
		)
		(fp_line
			(start 0.67945 0.3048)
			(end 0.120396 0.3048)
			(stroke
				(width 0.1)
				(type default)
			)
			(layer "F.Fab")
		)
		(fp_line
			(start -0.12065 0.2794)
			(end -0.12065 0.3048)
			(stroke
				(width 0.1)
				(type default)
			)
			(layer "F.Fab")
		)
		(fp_line
			(start 0.120396 0.2794)
			(end -0.12065 0.2794)
			(stroke
				(width 0.1)
				(type default)
			)
			(layer "F.Fab")
		)
		(fp_line
			(start -0.12065 -0.2794)
			(end 0.12065 -0.2794)
			(stroke
				(width 0.1)
				(type default)
			)
			(layer "F.Fab")
		)
		(fp_line
			(start 0.12065 -0.2794)
			(end 0.12065 -0.3048)
			(stroke
				(width 0.1)
				(type default)
			)
			(layer "F.Fab")
		)
		(fp_line
			(start 0.12065 -0.3048)
			(end 0.67945 -0.3048)
			(stroke
				(width 0.1)
				(type default)
			)
			(layer "F.Fab")
		)
		(fp_line
			(start 0.67945 -0.3048)
			(end 0.67945 0.3048)
			(stroke
				(width 0.1)
				(type default)
			)
			(layer "F.Fab")
		)
		(fp_line
			(start -0.67945 -0.305054)
			(end -0.12065 -0.305054)
			(stroke
				(width 0.1)
				(type default)
			)
			(layer "F.Fab")
		)
		(fp_line
			(start -0.12065 -0.305054)
			(end -0.12065 -0.2794)
			(stroke
				(width 0.1)
				(type default)
			)
			(layer "F.Fab")
		)
		(pad "1" smd circle
			(at -0.40005 0 270)
			(size 0 0)
			(layers "F.Cu" "F.Mask" "F.Paste")
			(net "SEL_FLASH_PEX0_BUF")
		)
		(pad "2" smd circle
			(at 0.40005 0 270)
			(size 0 0)
			(layers "F.Cu" "F.Mask" "F.Paste")
			(net "SEL_FLASH_PEX0_BUF_R")
		)
	)
	(footprint ""
		(layer "F.Cu")
		(at 190.141352 -350.098614 90)
		(property "Reference" "C374"
			(at 0 0 90)
			(layer "F.SilkS")
			(hide yes)
			(effects
				(font
					(size 1.27 1.27)
				)
			)
		)
		(property "Value" ""
			(at 0 0 90)
			(layer "F.Fab")
			(effects
				(font
					(size 1.27 1.27)
				)
			)
		)
		(duplicate_pad_numbers_are_jumpers no)
		(fp_line
			(start 0.299974 -0.150114)
			(end 0.299974 0.150114)
			(stroke
				(width 0.1)
				(type default)
			)
			(layer "F.Fab")
		)
		(fp_line
			(start -0.299974 -0.150114)
			(end 0.299974 -0.150114)
			(stroke
				(width 0.1)
				(type default)
			)
			(layer "F.Fab")
		)
		(fp_line
			(start 0.299974 0.150114)
			(end -0.299974 0.150114)
			(stroke
				(width 0.1)
				(type default)
			)
			(layer "F.Fab")
		)
		(fp_line
			(start -0.299974 0.150114)
			(end -0.299974 -0.150114)
			(stroke
				(width 0.1)
				(type default)
			)
			(layer "F.Fab")
		)
		(pad "1" smd rect
			(at -0.2667 0 90)
			(size 0.3048 0.381)
			(layers "F.Cu" "F.Mask" "F.Paste")
			(net "P5E_PEX1_STN7_TX_DP<126>")
		)
		(pad "2" smd rect
			(at 0.2667 0 90)
			(size 0.3048 0.381)
			(layers "F.Cu" "F.Mask" "F.Paste")
			(net "P5E_PEX1_STN7_TX_C_DP<126>")
		)
	)
)
